(kicad_pcb
	(version 20260206)
	(generator "pcbnew")
	(generator_version "10.0")
	(general
		(thickness 1.6)
		(legacy_teardrops no)
	)
	(paper "A4")
	(title_block
		(title "03242023_DA0F0TMBIJ0_F0T_Motherboard_J_brd_V01_OCP.brd")
		(comment 1 "Grand Teton / footprints 1042-1047 of 6105")
	)
	(layers
		(0 "F.Cu" signal "TOP")
		(4 "In1.Cu" signal "GND")
		(6 "In2.Cu" signal "IN1")
		(8 "In3.Cu" signal "GND1")
		(10 "In4.Cu" signal "IN2")
		(12 "In5.Cu" signal "GND2")
		(14 "In6.Cu" signal "IN3")
		(16 "In7.Cu" signal "GND3")
		(18 "In8.Cu" signal "VCC")
		(20 "In9.Cu" signal "VCC1")
		(22 "In10.Cu" signal "GND4")
		(24 "In11.Cu" signal "IN4")
		(26 "In12.Cu" signal "GND5")
		(28 "In13.Cu" signal "IN5")
		(30 "In14.Cu" signal "GND6")
		(32 "In15.Cu" signal "IN6")
		(34 "In16.Cu" signal "GND7")
		(2 "B.Cu" signal "BOTTOM")
		(9 "F.Adhes" user "F.Adhesive")
		(11 "B.Adhes" user "B.Adhesive")
		(13 "F.Paste" user "Package Geometry/Pastemask Top")
		(15 "B.Paste" user "Package Geometry/Pastemask Bottom")
		(5 "F.SilkS" user "Ref Des/Silkscreen Top")
		(7 "B.SilkS" user "Ref Des/Silkscreen Bottom")
		(1 "F.Mask" user "Board Geometry/Soldermask Top")
		(3 "B.Mask" user "Board Geometry/Soldermask Bottom")
		(17 "Dwgs.User" user "User.Drawings")
		(19 "Cmts.User" user "User.Comments")
		(21 "Eco1.User" user "User.Eco1")
		(23 "Eco2.User" user "User.Eco2")
		(25 "Edge.Cuts" user "Board Geometry/Outline")
		(27 "Margin" user)
		(31 "F.CrtYd" user "Package Geometry/Place Bound Top")
		(29 "B.CrtYd" user "Package Geometry/Place Bound Bottom")
		(35 "F.Fab" user "Ref Des/Assembly Top")
		(33 "B.Fab" user "Ref Des/Assembly Bottom")
	)
	(footprint ""
		(layer "F.Cu")
		(at 105.21188 -425.795948 180)
		(property "Reference" "R4213"
			(at 0 0 180)
			(layer "F.SilkS")
			(hide yes)
			(effects
				(font
					(size 1.27 1.27)
				)
			)
		)
		(property "Value" ""
			(at 0 0 180)
			(layer "F.Fab")
			(effects
				(font
					(size 1.27 1.27)
				)
			)
		)
		(duplicate_pad_numbers_are_jumpers no)
		(fp_line
			(start 0.7874 0.4064)
			(end -0.7874 0.4064)
			(stroke
				(width 0.1524)
				(type default)
			)
			(layer "F.SilkS")
		)
		(fp_line
			(start 0.7874 -0.4064)
			(end 0.7874 0.4064)
			(stroke
				(width 0.1524)
				(type default)
			)
			(layer "F.SilkS")
		)
		(fp_line
			(start -0.7874 0.4064)
			(end -0.7874 -0.4064)
			(stroke
				(width 0.1524)
				(type default)
			)
			(layer "F.SilkS")
		)
		(fp_line
			(start -0.7874 -0.4064)
			(end 0.7874 -0.4064)
			(stroke
				(width 0.1524)
				(type default)
			)
			(layer "F.SilkS")
		)
		(fp_line
			(start 0.67945 0.3048)
			(end 0.120396 0.3048)
			(stroke
				(width 0.1)
				(type default)
			)
			(layer "F.Fab")
		)
		(fp_line
			(start 0.67945 -0.3048)
			(end 0.67945 0.3048)
			(stroke
				(width 0.1)
				(type default)
			)
			(layer "F.Fab")
		)
		(fp_line
			(start 0.12065 -0.2794)
			(end 0.12065 -0.3048)
			(stroke
				(width 0.1)
				(type default)
			)
			(layer "F.Fab")
		)
		(fp_line
			(start 0.12065 -0.3048)
			(end 0.67945 -0.3048)
			(stroke
				(width 0.1)
				(type default)
			)
			(layer "F.Fab")
		)
		(fp_line
			(start 0.120396 0.3048)
			(end 0.120396 0.2794)
			(stroke
				(width 0.1)
				(type default)
			)
			(layer "F.Fab")
		)
		(fp_line
			(start 0.120396 0.2794)
			(end -0.12065 0.2794)
			(stroke
				(width 0.1)
				(type default)
			)
			(layer "F.Fab")
		)
		(fp_line
			(start -0.12065 0.3048)
			(end -0.67945 0.3048)
			(stroke
				(width 0.1)
				(type default)
			)
			(layer "F.Fab")
		)
		(fp_line
			(start -0.12065 0.2794)
			(end -0.12065 0.3048)
			(stroke
				(width 0.1)
				(type default)
			)
			(layer "F.Fab")
		)
		(fp_line
			(start -0.12065 -0.2794)
			(end 0.12065 -0.2794)
			(stroke
				(width 0.1)
				(type default)
			)
			(layer "F.Fab")
		)
		(fp_line
			(start -0.12065 -0.305054)
			(end -0.12065 -0.2794)
			(stroke
				(width 0.1)
				(type default)
			)
			(layer "F.Fab")
		)
		(fp_line
			(start -0.67945 0.3048)
			(end -0.67945 -0.305054)
			(stroke
				(width 0.1)
				(type default)
			)
			(layer "F.Fab")
		)
		(fp_line
			(start -0.67945 -0.305054)
			(end -0.12065 -0.305054)
			(stroke
				(width 0.1)
				(type default)
			)
			(layer "F.Fab")
		)
		(pad "1" smd circle
			(at -0.40005 0 180)
			(size 0 0)
			(layers "F.Cu" "F.Mask" "F.Paste")
			(net "FM_THERMAL_ALERT_N")
		)
		(pad "2" smd circle
			(at 0.40005 0 180)
			(size 0 0)
			(layers "F.Cu" "F.Mask" "F.Paste")
			(net "FM_LM75_2_ALERT_N")
		)
	)
	(footprint ""
		(layer "F.Cu")
		(at 201.00036 -115.534948 180)
		(property "Reference" "R4144"
			(at 0 0 180)
			(layer "F.SilkS")
			(hide yes)
			(effects
				(font
					(size 1.27 1.27)
				)
			)
		)
		(property "Value" ""
			(at 0 0 180)
			(layer "F.Fab")
			(effects
				(font
					(size 1.27 1.27)
				)
			)
		)
		(duplicate_pad_numbers_are_jumpers no)
		(fp_line
			(start 0.7874 0.4064)
			(end -0.7874 0.4064)
			(stroke
				(width 0.1524)
				(type default)
			)
			(layer "F.SilkS")
		)
		(fp_line
			(start 0.7874 -0.4064)
			(end 0.7874 0.4064)
			(stroke
				(width 0.1524)
				(type default)
			)
			(layer "F.SilkS")
		)
		(fp_line
			(start -0.7874 0.4064)
			(end -0.7874 -0.4064)
			(stroke
				(width 0.1524)
				(type default)
			)
			(layer "F.SilkS")
		)
		(fp_line
			(start -0.7874 -0.4064)
			(end 0.7874 -0.4064)
			(stroke
				(width 0.1524)
				(type default)
			)
			(layer "F.SilkS")
		)
		(fp_line
			(start 0.67945 0.3048)
			(end 0.120396 0.3048)
			(stroke
				(width 0.1)
				(type default)
			)
			(layer "F.Fab")
		)
		(fp_line
			(start 0.67945 -0.3048)
			(end 0.67945 0.3048)
			(stroke
				(width 0.1)
				(type default)
			)
			(layer "F.Fab")
		)
		(fp_line
			(start 0.12065 -0.2794)
			(end 0.12065 -0.3048)
			(stroke
				(width 0.1)
				(type default)
			)
			(layer "F.Fab")
		)
		(fp_line
			(start 0.12065 -0.3048)
			(end 0.67945 -0.3048)
			(stroke
				(width 0.1)
				(type default)
			)
			(layer "F.Fab")
		)
		(fp_line
			(start 0.120396 0.3048)
			(end 0.120396 0.2794)
			(stroke
				(width 0.1)
				(type default)
			)
			(layer "F.Fab")
		)
		(fp_line
			(start 0.120396 0.2794)
			(end -0.12065 0.2794)
			(stroke
				(width 0.1)
				(type default)
			)
			(layer "F.Fab")
		)
		(fp_line
			(start -0.12065 0.3048)
			(end -0.67945 0.3048)
			(stroke
				(width 0.1)
				(type default)
			)
			(layer "F.Fab")
		)
		(fp_line
			(start -0.12065 0.2794)
			(end -0.12065 0.3048)
			(stroke
				(width 0.1)
				(type default)
			)
			(layer "F.Fab")
		)
		(fp_line
			(start -0.12065 -0.2794)
			(end 0.12065 -0.2794)
			(stroke
				(width 0.1)
				(type default)
			)
			(layer "F.Fab")
		)
		(fp_line
			(start -0.12065 -0.305054)
			(end -0.12065 -0.2794)
			(stroke
				(width 0.1)
				(type default)
			)
			(layer "F.Fab")
		)
		(fp_line
			(start -0.67945 0.3048)
			(end -0.67945 -0.305054)
			(stroke
				(width 0.1)
				(type default)
			)
			(layer "F.Fab")
		)
		(fp_line
			(start -0.67945 -0.305054)
			(end -0.12065 -0.305054)
			(stroke
				(width 0.1)
				(type default)
			)
			(layer "F.Fab")
		)
		(pad "1" smd circle
			(at -0.40005 0 180)
			(size 0 0)
			(layers "F.Cu" "F.Mask" "F.Paste")
			(net "GPU_3V3IO_RSVD1_FFU_ISO")
		)
		(pad "2" smd circle
			(at 0.40005 0 180)
			(size 0 0)
			(layers "F.Cu" "F.Mask" "F.Paste")
			(net "GPU_3V3IO_RSVD1_FFU_ISO_R")
		)
	)
	(footprint ""
		(layer "F.Cu")
		(at 191.29629 -30.269688 180)
		(property "Reference" "PR4526"
			(at 0 0 180)
			(layer "F.SilkS")
			(hide yes)
			(effects
				(font
					(size 1.27 1.27)
				)
			)
		)
		(property "Value" ""
			(at 0 0 180)
			(layer "F.Fab")
			(effects
				(font
					(size 1.27 1.27)
				)
			)
		)
		(duplicate_pad_numbers_are_jumpers no)
		(fp_line
			(start 0.7874 0.4064)
			(end -0.7874 0.4064)
			(stroke
				(width 0.1524)
				(type default)
			)
			(layer "F.SilkS")
		)
		(fp_line
			(start 0.7874 -0.4064)
			(end 0.7874 0.4064)
			(stroke
				(width 0.1524)
				(type default)
			)
			(layer "F.SilkS")
		)
		(fp_line
			(start -0.7874 0.4064)
			(end -0.7874 -0.4064)
			(stroke
				(width 0.1524)
				(type default)
			)
			(layer "F.SilkS")
		)
		(fp_line
			(start -0.7874 -0.4064)
			(end 0.7874 -0.4064)
			(stroke
				(width 0.1524)
				(type default)
			)
			(layer "F.SilkS")
		)
		(fp_line
			(start 0.67945 0.3048)
			(end 0.120396 0.3048)
			(stroke
				(width 0.1)
				(type default)
			)
			(layer "F.Fab")
		)
		(fp_line
			(start 0.67945 -0.3048)
			(end 0.67945 0.3048)
			(stroke
				(width 0.1)
				(type default)
			)
			(layer "F.Fab")
		)
		(fp_line
			(start 0.12065 -0.2794)
			(end 0.12065 -0.3048)
			(stroke
				(width 0.1)
				(type default)
			)
			(layer "F.Fab")
		)
		(fp_line
			(start 0.12065 -0.3048)
			(end 0.67945 -0.3048)
			(stroke
				(width 0.1)
				(type default)
			)
			(layer "F.Fab")
		)
		(fp_line
			(start 0.120396 0.3048)
			(end 0.120396 0.2794)
			(stroke
				(width 0.1)
				(type default)
			)
			(layer "F.Fab")
		)
		(fp_line
			(start 0.120396 0.2794)
			(end -0.12065 0.2794)
			(stroke
				(width 0.1)
				(type default)
			)
			(layer "F.Fab")
		)
		(fp_line
			(start -0.12065 0.3048)
			(end -0.67945 0.3048)
			(stroke
				(width 0.1)
				(type default)
			)
			(layer "F.Fab")
		)
		(fp_line
			(start -0.12065 0.2794)
			(end -0.12065 0.3048)
			(stroke
				(width 0.1)
				(type default)
			)
			(layer "F.Fab")
		)
		(fp_line
			(start -0.12065 -0.2794)
			(end 0.12065 -0.2794)
			(stroke
				(width 0.1)
				(type default)
			)
			(layer "F.Fab")
		)
		(fp_line
			(start -0.12065 -0.305054)
			(end -0.12065 -0.2794)
			(stroke
				(width 0.1)
				(type default)
			)
			(layer "F.Fab")
		)
		(fp_line
			(start -0.67945 0.3048)
			(end -0.67945 -0.305054)
			(stroke
				(width 0.1)
				(type default)
			)
			(layer "F.Fab")
		)
		(fp_line
			(start -0.67945 -0.305054)
			(end -0.12065 -0.305054)
			(stroke
				(width 0.1)
				(type default)
			)
			(layer "F.Fab")
		)
		(pad "1" smd circle
			(at -0.40005 0 180)
			(size 0 0)
			(layers "F.Cu" "F.Mask" "F.Paste")
			(net "P12V_SCM_R")
		)
		(pad "2" smd circle
			(at 0.40005 0 180)
			(size 0 0)
			(layers "F.Cu" "F.Mask" "F.Paste")
			(net "P12V_SCM_GATE")
		)
	)
	(footprint ""
		(layer "F.Cu")
		(at 139.505944 -366.066578 90)
		(property "Reference" "PJP1"
			(at 3.7973 4.352036 0)
			(unlocked yes)
			(layer "F.SilkS")
			(effects
				(font
					(size 0.7874 0.5842)
					(thickness 0.1524)
				)
				(justify left)
			)
		)
		(property "Value" ""
			(at 0 0 90)
			(layer "F.Fab")
			(effects
				(font
					(size 1.27 1.27)
				)
			)
		)
		(duplicate_pad_numbers_are_jumpers no)
		(fp_line
			(start 1.249934 -1.320038)
			(end 1.249934 6.400038)
			(stroke
				(width 0.1524)
				(type default)
			)
			(layer "F.SilkS")
		)
		(fp_line
			(start -1.249934 -1.320038)
			(end 1.249934 -1.320038)
			(stroke
				(width 0.1524)
				(type default)
			)
			(layer "F.SilkS")
		)
		(fp_line
			(start 1.249934 6.400038)
			(end -1.249934 6.400038)
			(stroke
				(width 0.1524)
				(type default)
			)
			(layer "F.SilkS")
		)
		(fp_line
			(start -1.249934 6.400038)
			(end -1.249934 -1.320038)
			(stroke
				(width 0.1524)
				(type default)
			)
			(layer "F.SilkS")
		)
		(fp_poly
			(pts
				(xy -1.668272 -0.08636) (xy -2.7813 0.470154) (xy -2.7813 -0.642874)
			)
			(stroke
				(width 0)
				(type default)
			)
			(fill yes)
			(layer "F.SilkS")
		)
		(fp_line
			(start 1.249934 -1.320038)
			(end 1.249934 6.400038)
			(stroke
				(width 0.1)
				(type default)
			)
			(layer "F.Fab")
		)
		(fp_line
			(start -1.249934 -1.320038)
			(end 1.249934 -1.320038)
			(stroke
				(width 0.1)
				(type default)
			)
			(layer "F.Fab")
		)
		(fp_line
			(start 1.249934 6.400038)
			(end -1.249934 6.400038)
			(stroke
				(width 0.1)
				(type default)
			)
			(layer "F.Fab")
		)
		(fp_line
			(start -1.249934 6.400038)
			(end -1.249934 -1.320038)
			(stroke
				(width 0.1)
				(type default)
			)
			(layer "F.Fab")
		)
		(fp_poly
			(pts
				(xy -2.5654 -0.556514) (xy -1.452372 0) (xy -2.5654 0.556514)
			)
			(stroke
				(width 0)
				(type default)
			)
			(fill yes)
			(layer "F.Fab")
		)
		(fp_text user "3"
			(at -2.01676 5.393436 0)
			(unlocked yes)
			(layer "F.SilkS")
			(effects
				(font
					(size 0.7874 0.5842)
					(thickness 0.1524)
				)
			)
		)
		(fp_text user "1"
			(at -1.143 0.02667 90)
			(unlocked yes)
			(layer "B.SilkS")
			(effects
				(font
					(size 0.7874 0.5842)
					(thickness 0.1524)
				)
				(justify mirror)
			)
		)
		(fp_text user "3"
			(at -1.1557 5.18287 90)
			(unlocked yes)
			(layer "B.SilkS")
			(effects
				(font
					(size 0.7874 0.5842)
					(thickness 0.1524)
				)
				(justify mirror)
			)
		)
		(fp_text user "1"
			(at -1.143 0.02667 90)
			(unlocked yes)
			(layer "B.Fab")
			(effects
				(font
					(size 0.7874 0.5842)
					(thickness 0.1524)
				)
				(justify mirror)
			)
		)
		(fp_text user "3"
			(at -1.1557 5.18287 90)
			(unlocked yes)
			(layer "B.Fab")
			(effects
				(font
					(size 0.7874 0.5842)
					(thickness 0.1524)
				)
				(justify mirror)
			)
		)
		(fp_text user "3"
			(at -1.778 5.13207 90)
			(unlocked yes)
			(layer "F.Fab")
			(effects
				(font
					(size 0.7874 0.5842)
					(thickness 0.1524)
				)
			)
		)
		(pad "1" thru_hole rect
			(at 0 0 90)
			(size 1.5494 1.5494)
			(drill 1.0414)
			(layers "*.Cu" "*.Mask")
			(remove_unused_layers no)
			(net "SMB_VR_3V3AUX_SCL_R3")
			(clearance 0)
			(padstack
				(mode front_inner_back)
				(layer "Inner"
					(shape circle)
					(size 1.5494 1.5494)
					(clearance 0)
				)
				(layer "B.Cu"
					(shape rect)
					(size 1.5494 1.5494)
					(clearance 0)
				)
			)
		)
		(pad "2" thru_hole circle
			(at 0 2.54 90)
			(size 1.5494 1.5494)
			(drill 1.0414)
			(layers "*.Cu" "*.Mask")
			(remove_unused_layers no)
			(net "GND")
			(clearance 0)
		)
		(pad "3" thru_hole circle
			(at 0 5.08 90)
			(size 1.5494 1.5494)
			(drill 1.0414)
			(layers "*.Cu" "*.Mask")
			(remove_unused_layers no)
			(net "SMB_VR_3V3AUX_SDA_R3")
			(clearance 0)
		)
	)
	(footprint ""
		(layer "F.Cu")
		(at 12.51712 -85.700108)
		(property "Reference" "H28"
			(at -5.94614 -2.116328 0)
			(unlocked yes)
			(layer "F.SilkS")
			(effects
				(font
					(size 0.7874 0.5842)
					(thickness 0.1524)
				)
				(justify left)
			)
		)
		(property "Value" ""
			(at 0 0 0)
			(layer "F.Fab")
			(effects
				(font
					(size 1.27 1.27)
				)
			)
		)
		(duplicate_pad_numbers_are_jumpers no)
		(fp_circle
			(center 0 0)
			(end 2.4003 0)
			(stroke
				(width 0.1524)
				(type default)
			)
			(fill no)
			(layer "F.SilkS")
		)
		(fp_circle
			(center 0 0)
			(end 6.5913 0)
			(stroke
				(width 0.1524)
				(type default)
			)
			(fill no)
			(layer "B.SilkS")
		)
		(fp_circle
			(center 0 0)
			(end 6.5913 0)
			(stroke
				(width 0.1)
				(type default)
			)
			(fill no)
			(layer "B.Fab")
		)
		(fp_circle
			(center 0 0)
			(end 2.4003 0)
			(stroke
				(width 0.1)
				(type default)
			)
			(fill no)
			(layer "F.Fab")
		)
		(pad "" np_thru_hole circle
			(at 0 0)
			(size 3.175 3.175)
			(drill 3.175)
			(layers "*.Cu" "*.Mask")
			(clearance 0.381)
			(thermal_gap 0.381)
		)
		(zone
			(layers "F.Cu" "B.Cu" "In1.Cu" "In2.Cu" "In3.Cu" "In4.Cu" "In5.Cu" "In6.Cu"
				"In7.Cu" "In8.Cu" "In9.Cu" "In10.Cu" "In11.Cu" "In12.Cu" "In13.Cu" "In14.Cu"
				"In15.Cu" "In16.Cu"
			)
			(hatch none 0.5)
			(connect_pads
				(clearance 0)
			)
			(min_thickness 0.25)
			(keepout
				(tracks not_allowed)
				(vias allowed)
				(pads allowed)
				(copperpour not_allowed)
				(footprints allowed)
			)
			(placement
				(enabled no)
				(sheetname "")
			)
			(fill
				(thermal_gap 0.5)
				(thermal_bridge_width 0.5)
				(island_removal_mode 0)
			)
			(polygon
				(pts
					(arc
						(start 14.61262 -85.700108)
						(mid 10.42162 -85.700108)
						(end 14.61262 -85.700108)
					)
				)
			)
		)
	)
	(footprint ""
		(layer "F.Cu")
		(at 116.888006 -333.804514 -90)
		(property "Reference" "PC530_P1_3"
			(at 0 0 270)
			(layer "F.SilkS")
			(hide yes)
			(effects
				(font
					(size 1.27 1.27)
				)
			)
		)
		(property "Value" ""
			(at 0 0 270)
			(layer "F.Fab")
			(effects
				(font
					(size 1.27 1.27)
				)
			)
		)
		(duplicate_pad_numbers_are_jumpers no)
		(fp_line
			(start -0.7874 0.4064)
			(end -0.7874 -0.4064)
			(stroke
				(width 0.1524)
				(type default)
			)
			(layer "F.SilkS")
		)
		(fp_line
			(start 0.7874 0.4064)
			(end -0.7874 0.4064)
			(stroke
				(width 0.1524)
				(type default)
			)
			(layer "F.SilkS")
		)
		(fp_line
			(start -0.7874 -0.4064)
			(end 0.7874 -0.4064)
			(stroke
				(width 0.1524)
				(type default)
			)
			(layer "F.SilkS")
		)
		(fp_line
			(start 0.7874 -0.4064)
			(end 0.7874 0.4064)
			(stroke
				(width 0.1524)
				(type default)
			)
			(layer "F.SilkS")
		)
		(fp_line
			(start -0.67945 0.3048)
			(end -0.67945 -0.305054)
			(stroke
				(width 0.1)
				(type default)
			)
			(layer "F.Fab")
		)
		(fp_line
			(start -0.12065 0.3048)
			(end -0.67945 0.3048)
			(stroke
				(width 0.1)
				(type default)
			)
			(layer "F.Fab")
		)
		(fp_line
			(start 0.120396 0.3048)
			(end 0.120396 0.2794)
			(stroke
				(width 0.1)
				(type default)
			)
			(layer "F.Fab")
		)
		(fp_line
			(start 0.67945 0.3048)
			(end 0.120396 0.3048)
			(stroke
				(width 0.1)
				(type default)
			)
			(layer "F.Fab")
		)
		(fp_line
			(start -0.12065 0.2794)
			(end -0.12065 0.3048)
			(stroke
				(width 0.1)
				(type default)
			)
			(layer "F.Fab")
		)
		(fp_line
			(start 0.120396 0.2794)
			(end -0.12065 0.2794)
			(stroke
				(width 0.1)
				(type default)
			)
			(layer "F.Fab")
		)
		(fp_line
			(start -0.12065 -0.2794)
			(end 0.12065 -0.2794)
			(stroke
				(width 0.1)
				(type default)
			)
			(layer "F.Fab")
		)
		(fp_line
			(start 0.12065 -0.2794)
			(end 0.12065 -0.3048)
			(stroke
				(width 0.1)
				(type default)
			)
			(layer "F.Fab")
		)
		(fp_line
			(start 0.12065 -0.3048)
			(end 0.67945 -0.3048)
			(stroke
				(width 0.1)
				(type default)
			)
			(layer "F.Fab")
		)
		(fp_line
			(start 0.67945 -0.3048)
			(end 0.67945 0.3048)
			(stroke
				(width 0.1)
				(type default)
			)
			(layer "F.Fab")
		)
		(fp_line
			(start -0.67945 -0.305054)
			(end -0.12065 -0.305054)
			(stroke
				(width 0.1)
				(type default)
			)
			(layer "F.Fab")
		)
		(fp_line
			(start -0.12065 -0.305054)
			(end -0.12065 -0.2794)
			(stroke
				(width 0.1)
				(type default)
			)
			(layer "F.Fab")
		)
		(pad "1" smd circle
			(at -0.40005 0 270)
			(size 0 0)
			(layers "F.Cu" "F.Mask" "F.Paste")
			(net "SW_P12V_PVCCIN_CPU1_FLT")
		)
		(pad "2" smd circle
			(at 0.40005 0 270)
			(size 0 0)
			(layers "F.Cu" "F.Mask" "F.Paste")
			(net "GND")
		)
	)
)
